# S9S_MB_2U (Grand Teton) — schematic netlist excerpt (pin names and nets, part order shuffled) for the footprints in the layout excerpt that follows; sources: Cadence DE-HDL packaged netlist, KiCad conversion of 03242023_DA0F0TMBIJ0_F0T_Motherboard_J_brd_V01_OCP.brd

R1844  Q_RES  33.2 1% CHIP  pkg 0402LF  page 222 : A = RST_PFR_OVR_SRTC_R ; B = RST_PFR_OVR_SRTC
PR640  Q_RES  0 5% EMPTY  pkg 0402LF  page 285 : A = P3V3 ; B = PVCCIN_CPU1_PVCC

(kicad_pcb
	(version 20260206)
	(generator "pcbnew")
	(generator_version "10.0")
	(general
		(thickness 1.6)
		(legacy_teardrops no)
	)
	(paper "A4")
	(title_block
		(title "03242023_DA0F0TMBIJ0_F0T_Motherboard_J_brd_V01_OCP.brd")
		(comment 1 "Grand Teton / footprints 1831-1832 of 6105")
	)
	(layers
		(0 "F.Cu" signal "TOP")
		(4 "In1.Cu" signal "GND")
		(6 "In2.Cu" signal "IN1")
		(8 "In3.Cu" signal "GND1")
		(10 "In4.Cu" signal "IN2")
		(12 "In5.Cu" signal "GND2")
		(14 "In6.Cu" signal "IN3")
		(16 "In7.Cu" signal "GND3")
		(18 "In8.Cu" signal "VCC")
		(20 "In9.Cu" signal "VCC1")
		(22 "In10.Cu" signal "GND4")
		(24 "In11.Cu" signal "IN4")
		(26 "In12.Cu" signal "GND5")
		(28 "In13.Cu" signal "IN5")
		(30 "In14.Cu" signal "GND6")
		(32 "In15.Cu" signal "IN6")
		(34 "In16.Cu" signal "GND7")
		(2 "B.Cu" signal "BOTTOM")
		(9 "F.Adhes" user "F.Adhesive")
		(11 "B.Adhes" user "B.Adhesive")
		(13 "F.Paste" user "Package Geometry/Pastemask Top")
		(15 "B.Paste" user "Package Geometry/Pastemask Bottom")
		(5 "F.SilkS" user "Ref Des/Silkscreen Top")
		(7 "B.SilkS" user "Ref Des/Silkscreen Bottom")
		(1 "F.Mask" user "Board Geometry/Soldermask Top")
		(3 "B.Mask" user "Board Geometry/Soldermask Bottom")
		(17 "Dwgs.User" user "User.Drawings")
		(19 "Cmts.User" user "User.Comments")
		(21 "Eco1.User" user "User.Eco1")
		(23 "Eco2.User" user "User.Eco2")
		(25 "Edge.Cuts" user "Board Geometry/Outline")
		(27 "Margin" user)
		(31 "F.CrtYd" user "Package Geometry/Place Bound Top")
		(29 "B.CrtYd" user "Package Geometry/Place Bound Bottom")
		(35 "F.Fab" user "Ref Des/Assembly Top")
		(33 "B.Fab" user "Ref Des/Assembly Bottom")
	)
	(footprint ""
		(layer "F.Cu")
		(at 144.54378 -345.129358 180)
		(property "Reference" "PR640"
			(at 0 0 180)
			(layer "F.SilkS")
			(hide yes)
			(effects
				(font
					(size 1.27 1.27)
				)
			)
		)
		(property "Value" ""
			(at 0 0 180)
			(layer "F.Fab")
			(effects
				(font
					(size 1.27 1.27)
				)
			)
		)
		(duplicate_pad_numbers_are_jumpers no)
		(fp_line
			(start 0.7874 0.4064)
			(end -0.7874 0.4064)
			(stroke
				(width 0.1524)
				(type default)
			)
			(layer "F.SilkS")
		)
		(fp_line
			(start 0.7874 -0.4064)
			(end 0.7874 0.4064)
			(stroke
				(width 0.1524)
				(type default)
			)
			(layer "F.SilkS")
		)
		(fp_line
			(start -0.7874 0.4064)
			(end -0.7874 -0.4064)
			(stroke
				(width 0.1524)
				(type default)
			)
			(layer "F.SilkS")
		)
		(fp_line
			(start -0.7874 -0.4064)
			(end 0.7874 -0.4064)
			(stroke
				(width 0.1524)
				(type default)
			)
			(layer "F.SilkS")
		)
		(fp_line
			(start 0.67945 0.3048)
			(end 0.120396 0.3048)
			(stroke
				(width 0.1)
				(type default)
			)
			(layer "F.Fab")
		)
		(fp_line
			(start 0.67945 -0.3048)
			(end 0.67945 0.3048)
			(stroke
				(width 0.1)
				(type default)
			)
			(layer "F.Fab")
		)
		(fp_line
			(start 0.12065 -0.2794)
			(end 0.12065 -0.3048)
			(stroke
				(width 0.1)
				(type default)
			)
			(layer "F.Fab")
		)
		(fp_line
			(start 0.12065 -0.3048)
			(end 0.67945 -0.3048)
			(stroke
				(width 0.1)
				(type default)
			)
			(layer "F.Fab")
		)
		(fp_line
			(start 0.120396 0.3048)
			(end 0.120396 0.2794)
			(stroke
				(width 0.1)
				(type default)
			)
			(layer "F.Fab")
		)
		(fp_line
			(start 0.120396 0.2794)
			(end -0.12065 0.2794)
			(stroke
				(width 0.1)
				(type default)
			)
			(layer "F.Fab")
		)
		(fp_line
			(start -0.12065 0.3048)
			(end -0.67945 0.3048)
			(stroke
				(width 0.1)
				(type default)
			)
			(layer "F.Fab")
		)
		(fp_line
			(start -0.12065 0.2794)
			(end -0.12065 0.3048)
			(stroke
				(width 0.1)
				(type default)
			)
			(layer "F.Fab")
		)
		(fp_line
			(start -0.12065 -0.2794)
			(end 0.12065 -0.2794)
			(stroke
				(width 0.1)
				(type default)
			)
			(layer "F.Fab")
		)
		(fp_line
			(start -0.12065 -0.305054)
			(end -0.12065 -0.2794)
			(stroke
				(width 0.1)
				(type default)
			)
			(layer "F.Fab")
		)
		(fp_line
			(start -0.67945 0.3048)
			(end -0.67945 -0.305054)
			(stroke
				(width 0.1)
				(type default)
			)
			(layer "F.Fab")
		)
		(fp_line
			(start -0.67945 -0.305054)
			(end -0.12065 -0.305054)
			(stroke
				(width 0.1)
				(type default)
			)
			(layer "F.Fab")
		)
		(pad "1" smd circle
			(at -0.40005 0 180)
			(size 0 0)
			(layers "F.Cu" "F.Mask" "F.Paste")
			(net "P3V3")
		)
		(pad "2" smd circle
			(at 0.40005 0 180)
			(size 0 0)
			(layers "F.Cu" "F.Mask" "F.Paste")
			(net "PVCCIN_CPU1_PVCC")
		)
	)
	(footprint ""
		(layer "F.Cu")
		(at 197.41388 -103.685848)
		(property "Reference" "R1844"
			(at 0 0 0)
			(layer "F.SilkS")
			(hide yes)
			(effects
				(font
					(size 1.27 1.27)
				)
			)
		)
		(property "Value" ""
			(at 0 0 0)
			(layer "F.Fab")
			(effects
				(font
					(size 1.27 1.27)
				)
			)
		)
		(duplicate_pad_numbers_are_jumpers no)
		(fp_line
			(start -0.7874 -0.4064)
			(end 0.7874 -0.4064)
			(stroke
				(width 0.1524)
				(type default)
			)
			(layer "F.SilkS")
		)
		(fp_line
			(start -0.7874 0.4064)
			(end -0.7874 -0.4064)
			(stroke
				(width 0.1524)
				(type default)
			)
			(layer "F.SilkS")
		)
		(fp_line
			(start 0.7874 -0.4064)
			(end 0.7874 0.4064)
			(stroke
				(width 0.1524)
				(type default)
			)
			(layer "F.SilkS")
		)
		(fp_line
			(start 0.7874 0.4064)
			(end -0.7874 0.4064)
			(stroke
				(width 0.1524)
				(type default)
			)
			(layer "F.SilkS")
		)
		(fp_line
			(start -0.67945 -0.305054)
			(end -0.12065 -0.305054)
			(stroke
				(width 0.1)
				(type default)
			)
			(layer "F.Fab")
		)
		(fp_line
			(start -0.67945 0.3048)
			(end -0.67945 -0.305054)
			(stroke
				(width 0.1)
				(type default)
			)
			(layer "F.Fab")
		)
		(fp_line
			(start -0.12065 -0.305054)
			(end -0.12065 -0.2794)
			(stroke
				(width 0.1)
				(type default)
			)
			(layer "F.Fab")
		)
		(fp_line
			(start -0.12065 -0.2794)
			(end 0.12065 -0.2794)
			(stroke
				(width 0.1)
				(type default)
			)
			(layer "F.Fab")
		)
		(fp_line
			(start -0.12065 0.2794)
			(end -0.12065 0.3048)
			(stroke
				(width 0.1)
				(type default)
			)
			(layer "F.Fab")
		)
		(fp_line
			(start -0.12065 0.3048)
			(end -0.67945 0.3048)
			(stroke
				(width 0.1)
				(type default)
			)
			(layer "F.Fab")
		)
		(fp_line
			(start 0.120396 0.2794)
			(end -0.12065 0.2794)
			(stroke
				(width 0.1)
				(type default)
			)
			(layer "F.Fab")
		)
		(fp_line
			(start 0.120396 0.3048)
			(end 0.120396 0.2794)
			(stroke
				(width 0.1)
				(type default)
			)
			(layer "F.Fab")
		)
		(fp_line
			(start 0.12065 -0.3048)
			(end 0.67945 -0.3048)
			(stroke
				(width 0.1)
				(type default)
			)
			(layer "F.Fab")
		)
		(fp_line
			(start 0.12065 -0.2794)
			(end 0.12065 -0.3048)
			(stroke
				(width 0.1)
				(type default)
			)
			(layer "F.Fab")
		)
		(fp_line
			(start 0.67945 -0.3048)
			(end 0.67945 0.3048)
			(stroke
				(width 0.1)
				(type default)
			)
			(layer "F.Fab")
		)
		(fp_line
			(start 0.67945 0.3048)
			(end 0.120396 0.3048)
			(stroke
				(width 0.1)
				(type default)
			)
			(layer "F.Fab")
		)
		(pad "1" smd circle
			(at -0.40005 0)
			(size 0 0)
			(layers "F.Cu" "F.Mask" "F.Paste")
			(net "RST_PFR_OVR_SRTC_R")
		)
		(pad "2" smd circle
			(at 0.40005 0)
			(size 0 0)
			(layers "F.Cu" "F.Mask" "F.Paste")
			(net "RST_PFR_OVR_SRTC")
		)
	)
)
